# S9S_MB_2U (Grand Teton) — schematic netlist excerpt (pin names and nets, part order shuffled) for the footprints in the layout excerpt that follows; sources: Cadence DE-HDL packaged netlist, KiCad conversion of 03242023_DA0F0TMBIJ0_F0T_Motherboard_J_brd_V01_OCP.brd

R4583  Q_RES  1K 1% CHIP  pkg 0402LF  page 195 : A = FM_BOARD_BMC_SKU_ID1 ; B = GND
R3862  Q_RES  0 5% CHIP  pkg 0402LF  page 250 : A = P12V_OCP_V3_2_ISENSE_MPS_TIC ; B = P12V_OCP_V3_2_ISENSE_TIC

(kicad_pcb
	(version 20260206)
	(generator "pcbnew")
	(generator_version "10.0")
	(general
		(thickness 1.6)
		(legacy_teardrops no)
	)
	(paper "A4")
	(title_block
		(title "03242023_DA0F0TMBIJ0_F0T_Motherboard_J_brd_V01_OCP.brd")
		(comment 1 "Grand Teton / footprints 327-328 of 6105")
	)
	(layers
		(0 "F.Cu" signal "TOP")
		(4 "In1.Cu" signal "GND")
		(6 "In2.Cu" signal "IN1")
		(8 "In3.Cu" signal "GND1")
		(10 "In4.Cu" signal "IN2")
		(12 "In5.Cu" signal "GND2")
		(14 "In6.Cu" signal "IN3")
		(16 "In7.Cu" signal "GND3")
		(18 "In8.Cu" signal "VCC")
		(20 "In9.Cu" signal "VCC1")
		(22 "In10.Cu" signal "GND4")
		(24 "In11.Cu" signal "IN4")
		(26 "In12.Cu" signal "GND5")
		(28 "In13.Cu" signal "IN5")
		(30 "In14.Cu" signal "GND6")
		(32 "In15.Cu" signal "IN6")
		(34 "In16.Cu" signal "GND7")
		(2 "B.Cu" signal "BOTTOM")
		(9 "F.Adhes" user "F.Adhesive")
		(11 "B.Adhes" user "B.Adhesive")
		(13 "F.Paste" user "Package Geometry/Pastemask Top")
		(15 "B.Paste" user "Package Geometry/Pastemask Bottom")
		(5 "F.SilkS" user "Ref Des/Silkscreen Top")
		(7 "B.SilkS" user "Ref Des/Silkscreen Bottom")
		(1 "F.Mask" user "Board Geometry/Soldermask Top")
		(3 "B.Mask" user "Board Geometry/Soldermask Bottom")
		(17 "Dwgs.User" user "User.Drawings")
		(19 "Cmts.User" user "User.Comments")
		(21 "Eco1.User" user "User.Eco1")
		(23 "Eco2.User" user "User.Eco2")
		(25 "Edge.Cuts" user "Board Geometry/Outline")
		(27 "Margin" user)
		(31 "F.CrtYd" user "Package Geometry/Place Bound Top")
		(29 "B.CrtYd" user "Package Geometry/Place Bound Bottom")
		(35 "F.Fab" user "Ref Des/Assembly Top")
		(33 "B.Fab" user "Ref Des/Assembly Bottom")
	)
	(footprint ""
		(layer "F.Cu")
		(at 175.4124 -94.338648 90)
		(property "Reference" "R4583"
			(at 0 0 90)
			(layer "F.SilkS")
			(hide yes)
			(effects
				(font
					(size 1.27 1.27)
				)
			)
		)
		(property "Value" ""
			(at 0 0 90)
			(layer "F.Fab")
			(effects
				(font
					(size 1.27 1.27)
				)
			)
		)
		(duplicate_pad_numbers_are_jumpers no)
		(fp_line
			(start 0.7874 -0.4064)
			(end 0.7874 0.4064)
			(stroke
				(width 0.1524)
				(type default)
			)
			(layer "F.SilkS")
		)
		(fp_line
			(start -0.7874 -0.4064)
			(end 0.7874 -0.4064)
			(stroke
				(width 0.1524)
				(type default)
			)
			(layer "F.SilkS")
		)
		(fp_line
			(start 0.7874 0.4064)
			(end -0.7874 0.4064)
			(stroke
				(width 0.1524)
				(type default)
			)
			(layer "F.SilkS")
		)
		(fp_line
			(start -0.7874 0.4064)
			(end -0.7874 -0.4064)
			(stroke
				(width 0.1524)
				(type default)
			)
			(layer "F.SilkS")
		)
		(fp_line
			(start -0.12065 -0.305054)
			(end -0.12065 -0.2794)
			(stroke
				(width 0.1)
				(type default)
			)
			(layer "F.Fab")
		)
		(fp_line
			(start -0.67945 -0.305054)
			(end -0.12065 -0.305054)
			(stroke
				(width 0.1)
				(type default)
			)
			(layer "F.Fab")
		)
		(fp_line
			(start 0.67945 -0.3048)
			(end 0.67945 0.3048)
			(stroke
				(width 0.1)
				(type default)
			)
			(layer "F.Fab")
		)
		(fp_line
			(start 0.12065 -0.3048)
			(end 0.67945 -0.3048)
			(stroke
				(width 0.1)
				(type default)
			)
			(layer "F.Fab")
		)
		(fp_line
			(start 0.12065 -0.2794)
			(end 0.12065 -0.3048)
			(stroke
				(width 0.1)
				(type default)
			)
			(layer "F.Fab")
		)
		(fp_line
			(start -0.12065 -0.2794)
			(end 0.12065 -0.2794)
			(stroke
				(width 0.1)
				(type default)
			)
			(layer "F.Fab")
		)
		(fp_line
			(start 0.120396 0.2794)
			(end -0.12065 0.2794)
			(stroke
				(width 0.1)
				(type default)
			)
			(layer "F.Fab")
		)
		(fp_line
			(start -0.12065 0.2794)
			(end -0.12065 0.3048)
			(stroke
				(width 0.1)
				(type default)
			)
			(layer "F.Fab")
		)
		(fp_line
			(start 0.67945 0.3048)
			(end 0.120396 0.3048)
			(stroke
				(width 0.1)
				(type default)
			)
			(layer "F.Fab")
		)
		(fp_line
			(start 0.120396 0.3048)
			(end 0.120396 0.2794)
			(stroke
				(width 0.1)
				(type default)
			)
			(layer "F.Fab")
		)
		(fp_line
			(start -0.12065 0.3048)
			(end -0.67945 0.3048)
			(stroke
				(width 0.1)
				(type default)
			)
			(layer "F.Fab")
		)
		(fp_line
			(start -0.67945 0.3048)
			(end -0.67945 -0.305054)
			(stroke
				(width 0.1)
				(type default)
			)
			(layer "F.Fab")
		)
		(pad "1" smd rect
			(at -0.40005 0 270)
			(size 0.4572 0.508)
			(layers "F.Cu" "F.Mask" "F.Paste")
			(net "FM_BOARD_BMC_SKU_ID1")
		)
		(pad "2" smd rect
			(at 0.40005 0 270)
			(size 0.4572 0.508)
			(layers "F.Cu" "F.Mask" "F.Paste")
			(net "GND")
		)
	)
	(footprint ""
		(layer "F.Cu")
		(at 40.627554 -110.587282 180)
		(property "Reference" "R3862"
			(at 0 0 180)
			(layer "F.SilkS")
			(hide yes)
			(effects
				(font
					(size 1.27 1.27)
				)
			)
		)
		(property "Value" ""
			(at 0 0 180)
			(layer "F.Fab")
			(effects
				(font
					(size 1.27 1.27)
				)
			)
		)
		(duplicate_pad_numbers_are_jumpers no)
		(fp_line
			(start 0.7874 0.4064)
			(end -0.7874 0.4064)
			(stroke
				(width 0.1524)
				(type default)
			)
			(layer "F.SilkS")
		)
		(fp_line
			(start 0.7874 -0.4064)
			(end 0.7874 0.4064)
			(stroke
				(width 0.1524)
				(type default)
			)
			(layer "F.SilkS")
		)
		(fp_line
			(start -0.7874 0.4064)
			(end -0.7874 -0.4064)
			(stroke
				(width 0.1524)
				(type default)
			)
			(layer "F.SilkS")
		)
		(fp_line
			(start -0.7874 -0.4064)
			(end 0.7874 -0.4064)
			(stroke
				(width 0.1524)
				(type default)
			)
			(layer "F.SilkS")
		)
		(fp_line
			(start 0.67945 0.3048)
			(end 0.120396 0.3048)
			(stroke
				(width 0.1)
				(type default)
			)
			(layer "F.Fab")
		)
		(fp_line
			(start 0.67945 -0.3048)
			(end 0.67945 0.3048)
			(stroke
				(width 0.1)
				(type default)
			)
			(layer "F.Fab")
		)
		(fp_line
			(start 0.12065 -0.2794)
			(end 0.12065 -0.3048)
			(stroke
				(width 0.1)
				(type default)
			)
			(layer "F.Fab")
		)
		(fp_line
			(start 0.12065 -0.3048)
			(end 0.67945 -0.3048)
			(stroke
				(width 0.1)
				(type default)
			)
			(layer "F.Fab")
		)
		(fp_line
			(start 0.120396 0.3048)
			(end 0.120396 0.2794)
			(stroke
				(width 0.1)
				(type default)
			)
			(layer "F.Fab")
		)
		(fp_line
			(start 0.120396 0.2794)
			(end -0.12065 0.2794)
			(stroke
				(width 0.1)
				(type default)
			)
			(layer "F.Fab")
		)
		(fp_line
			(start -0.12065 0.3048)
			(end -0.67945 0.3048)
			(stroke
				(width 0.1)
				(type default)
			)
			(layer "F.Fab")
		)
		(fp_line
			(start -0.12065 0.2794)
			(end -0.12065 0.3048)
			(stroke
				(width 0.1)
				(type default)
			)
			(layer "F.Fab")
		)
		(fp_line
			(start -0.12065 -0.2794)
			(end 0.12065 -0.2794)
			(stroke
				(width 0.1)
				(type default)
			)
			(layer "F.Fab")
		)
		(fp_line
			(start -0.12065 -0.305054)
			(end -0.12065 -0.2794)
			(stroke
				(width 0.1)
				(type default)
			)
			(layer "F.Fab")
		)
		(fp_line
			(start -0.67945 0.3048)
			(end -0.67945 -0.305054)
			(stroke
				(width 0.1)
				(type default)
			)
			(layer "F.Fab")
		)
		(fp_line
			(start -0.67945 -0.305054)
			(end -0.12065 -0.305054)
			(stroke
				(width 0.1)
				(type default)
			)
			(layer "F.Fab")
		)
		(pad "1" smd rect
			(at -0.40005 0)
			(size 0.4572 0.508)
			(layers "F.Cu" "F.Mask" "F.Paste")
			(net "P12V_OCP_V3_2_ISENSE_MPS_TIC")
		)
		(pad "2" smd rect
			(at 0.40005 0)
			(size 0.4572 0.508)
			(layers "F.Cu" "F.Mask" "F.Paste")
			(net "P12V_OCP_V3_2_ISENSE_TIC")
		)
	)
)
